# T6G (Grand Teton) — schematic netlist excerpt (pin names and nets, part order shuffled) for the footprints in the layout excerpt that follows; sources: Cadence DE-HDL packaged netlist, KiCad conversion of 04192023_DAF0TMB3IC0_F0TG_MB_C_brd_V02_OCP.brd

R1218  Q_RES  1K 1% CHIP  pkg 0201LF  page 186 : A = GND ; B = RT_ROM_MUX6_OE_N
R3182  Q_RES  10K 1% CHIP  pkg 0402LF  page 139 : A = P3V3_OCP_V3_2 ; B = IRQ_LVC3_OCP_V3_2_WAKE_N
R12  Q_RES  10K 1% CHIP  pkg 0402LF  page 83 : A = FM_I3C_CPU1_MUX0_OE_N ; B = GND

(kicad_pcb
	(version 20260206)
	(generator "pcbnew")
	(generator_version "10.0")
	(general
		(thickness 1.6)
		(legacy_teardrops no)
	)
	(paper "A4")
	(title_block
		(title "04192023_DAF0TMB3IC0_F0TG_MB_C_brd_V02_OCP.brd")
		(comment 1 "Grand Teton / footprints 4428-4430 of 8354")
	)
	(layers
		(0 "F.Cu" signal "TOP")
		(4 "In1.Cu" signal "GND")
		(6 "In2.Cu" signal "IN1")
		(8 "In3.Cu" signal "GND1")
		(10 "In4.Cu" signal "IN2")
		(12 "In5.Cu" signal "GND2")
		(14 "In6.Cu" signal "IN3")
		(16 "In7.Cu" signal "GND3")
		(18 "In8.Cu" signal "VCC")
		(20 "In9.Cu" signal "VCC1")
		(22 "In10.Cu" signal "GND4")
		(24 "In11.Cu" signal "IN4")
		(26 "In12.Cu" signal "GND5")
		(28 "In13.Cu" signal "IN5")
		(30 "In14.Cu" signal "GND6")
		(32 "In15.Cu" signal "IN6")
		(34 "In16.Cu" signal "GND7")
		(2 "B.Cu" signal "BOTTOM")
		(9 "F.Adhes" user "F.Adhesive")
		(11 "B.Adhes" user "B.Adhesive")
		(13 "F.Paste" user "Package Geometry/Pastemask Top")
		(15 "B.Paste" user "Package Geometry/Pastemask Bottom")
		(5 "F.SilkS" user "Ref Des/Silkscreen Top")
		(7 "B.SilkS" user "Ref Des/Silkscreen Bottom")
		(1 "F.Mask" user "Board Geometry/Soldermask Top")
		(3 "B.Mask" user "Board Geometry/Soldermask Bottom")
		(17 "Dwgs.User" user "User.Drawings")
		(19 "Cmts.User" user "User.Comments")
		(21 "Eco1.User" user "User.Eco1")
		(23 "Eco2.User" user "User.Eco2")
		(25 "Edge.Cuts" user "Board Geometry/Outline")
		(27 "Margin" user)
		(31 "F.CrtYd" user "Package Geometry/Place Bound Top")
		(29 "B.CrtYd" user "Package Geometry/Place Bound Bottom")
		(35 "F.Fab" user "Ref Des/Assembly Top")
		(33 "B.Fab" user "Ref Des/Assembly Bottom")
	)
	(footprint ""
		(layer "F.Cu")
		(at 171.20743 -103.96728)
		(property "Reference" "R12"
			(at 0 0 0)
			(layer "F.SilkS")
			(hide yes)
			(effects
				(font
					(size 1.27 1.27)
				)
			)
		)
		(property "Value" ""
			(at 0 0 0)
			(layer "F.Fab")
			(effects
				(font
					(size 1.27 1.27)
				)
			)
		)
		(duplicate_pad_numbers_are_jumpers no)
		(fp_line
			(start -0.7874 -0.4064)
			(end 0.7874 -0.4064)
			(stroke
				(width 0.1524)
				(type default)
			)
			(layer "F.SilkS")
		)
		(fp_line
			(start -0.7874 0.4064)
			(end -0.7874 -0.4064)
			(stroke
				(width 0.1524)
				(type default)
			)
			(layer "F.SilkS")
		)
		(fp_line
			(start 0.7874 -0.4064)
			(end 0.7874 0.4064)
			(stroke
				(width 0.1524)
				(type default)
			)
			(layer "F.SilkS")
		)
		(fp_line
			(start 0.7874 0.4064)
			(end -0.7874 0.4064)
			(stroke
				(width 0.1524)
				(type default)
			)
			(layer "F.SilkS")
		)
		(fp_line
			(start -0.67945 -0.305054)
			(end -0.12065 -0.305054)
			(stroke
				(width 0.1)
				(type default)
			)
			(layer "F.Fab")
		)
		(fp_line
			(start -0.67945 0.3048)
			(end -0.67945 -0.305054)
			(stroke
				(width 0.1)
				(type default)
			)
			(layer "F.Fab")
		)
		(fp_line
			(start -0.12065 -0.305054)
			(end -0.12065 -0.2794)
			(stroke
				(width 0.1)
				(type default)
			)
			(layer "F.Fab")
		)
		(fp_line
			(start -0.12065 -0.2794)
			(end 0.12065 -0.2794)
			(stroke
				(width 0.1)
				(type default)
			)
			(layer "F.Fab")
		)
		(fp_line
			(start -0.12065 0.2794)
			(end -0.12065 0.3048)
			(stroke
				(width 0.1)
				(type default)
			)
			(layer "F.Fab")
		)
		(fp_line
			(start -0.12065 0.3048)
			(end -0.67945 0.3048)
			(stroke
				(width 0.1)
				(type default)
			)
			(layer "F.Fab")
		)
		(fp_line
			(start 0.120396 0.2794)
			(end -0.12065 0.2794)
			(stroke
				(width 0.1)
				(type default)
			)
			(layer "F.Fab")
		)
		(fp_line
			(start 0.120396 0.3048)
			(end 0.120396 0.2794)
			(stroke
				(width 0.1)
				(type default)
			)
			(layer "F.Fab")
		)
		(fp_line
			(start 0.12065 -0.3048)
			(end 0.67945 -0.3048)
			(stroke
				(width 0.1)
				(type default)
			)
			(layer "F.Fab")
		)
		(fp_line
			(start 0.12065 -0.2794)
			(end 0.12065 -0.3048)
			(stroke
				(width 0.1)
				(type default)
			)
			(layer "F.Fab")
		)
		(fp_line
			(start 0.67945 -0.3048)
			(end 0.67945 0.3048)
			(stroke
				(width 0.1)
				(type default)
			)
			(layer "F.Fab")
		)
		(fp_line
			(start 0.67945 0.3048)
			(end 0.120396 0.3048)
			(stroke
				(width 0.1)
				(type default)
			)
			(layer "F.Fab")
		)
		(pad "1" smd circle
			(at -0.40005 0)
			(size 0 0)
			(layers "F.Cu" "F.Mask" "F.Paste")
			(net "FM_I3C_CPU1_MUX0_OE_N")
		)
		(pad "2" smd circle
			(at 0.40005 0)
			(size 0 0)
			(layers "F.Cu" "F.Mask" "F.Paste")
			(net "GND")
		)
	)
	(footprint ""
		(layer "F.Cu")
		(at 292.655244 -397.884396 -90)
		(property "Reference" "R1218"
			(at 0 0 270)
			(layer "F.SilkS")
			(hide yes)
			(effects
				(font
					(size 1.27 1.27)
				)
			)
		)
		(property "Value" ""
			(at 0 0 270)
			(layer "F.Fab")
			(effects
				(font
					(size 1.27 1.27)
				)
			)
		)
		(duplicate_pad_numbers_are_jumpers no)
		(fp_line
			(start -0.32512 0.175006)
			(end -0.32512 -0.175006)
			(stroke
				(width 0.1)
				(type default)
			)
			(layer "F.Fab")
		)
		(fp_line
			(start 0.32512 0.175006)
			(end -0.32512 0.175006)
			(stroke
				(width 0.1)
				(type default)
			)
			(layer "F.Fab")
		)
		(fp_line
			(start -0.32512 -0.175006)
			(end 0.32512 -0.175006)
			(stroke
				(width 0.1)
				(type default)
			)
			(layer "F.Fab")
		)
		(fp_line
			(start 0.32512 -0.175006)
			(end 0.32512 0.175006)
			(stroke
				(width 0.1)
				(type default)
			)
			(layer "F.Fab")
		)
		(pad "1" smd rect
			(at -0.2667 0 270)
			(size 0.3048 0.381)
			(layers "F.Cu" "F.Mask" "F.Paste")
			(net "GND")
		)
		(pad "2" smd rect
			(at 0.2667 0 90)
			(size 0.3048 0.381)
			(layers "F.Cu" "F.Mask" "F.Paste")
			(net "RT_ROM_MUX6_OE_N")
		)
	)
	(footprint ""
		(layer "F.Cu")
		(at 102.563422 -39.886636 180)
		(property "Reference" "R3182"
			(at 0 0 180)
			(layer "F.SilkS")
			(hide yes)
			(effects
				(font
					(size 1.27 1.27)
				)
			)
		)
		(property "Value" ""
			(at 0 0 180)
			(layer "F.Fab")
			(effects
				(font
					(size 1.27 1.27)
				)
			)
		)
		(duplicate_pad_numbers_are_jumpers no)
		(fp_line
			(start 0.7874 0.4064)
			(end -0.7874 0.4064)
			(stroke
				(width 0.1524)
				(type default)
			)
			(layer "F.SilkS")
		)
		(fp_line
			(start 0.7874 -0.4064)
			(end 0.7874 0.4064)
			(stroke
				(width 0.1524)
				(type default)
			)
			(layer "F.SilkS")
		)
		(fp_line
			(start -0.7874 0.4064)
			(end -0.7874 -0.4064)
			(stroke
				(width 0.1524)
				(type default)
			)
			(layer "F.SilkS")
		)
		(fp_line
			(start -0.7874 -0.4064)
			(end 0.7874 -0.4064)
			(stroke
				(width 0.1524)
				(type default)
			)
			(layer "F.SilkS")
		)
		(fp_line
			(start 0.67945 0.3048)
			(end 0.120396 0.3048)
			(stroke
				(width 0.1)
				(type default)
			)
			(layer "F.Fab")
		)
		(fp_line
			(start 0.67945 -0.3048)
			(end 0.67945 0.3048)
			(stroke
				(width 0.1)
				(type default)
			)
			(layer "F.Fab")
		)
		(fp_line
			(start 0.12065 -0.2794)
			(end 0.12065 -0.3048)
			(stroke
				(width 0.1)
				(type default)
			)
			(layer "F.Fab")
		)
		(fp_line
			(start 0.12065 -0.3048)
			(end 0.67945 -0.3048)
			(stroke
				(width 0.1)
				(type default)
			)
			(layer "F.Fab")
		)
		(fp_line
			(start 0.120396 0.3048)
			(end 0.120396 0.2794)
			(stroke
				(width 0.1)
				(type default)
			)
			(layer "F.Fab")
		)
		(fp_line
			(start 0.120396 0.2794)
			(end -0.12065 0.2794)
			(stroke
				(width 0.1)
				(type default)
			)
			(layer "F.Fab")
		)
		(fp_line
			(start -0.12065 0.3048)
			(end -0.67945 0.3048)
			(stroke
				(width 0.1)
				(type default)
			)
			(layer "F.Fab")
		)
		(fp_line
			(start -0.12065 0.2794)
			(end -0.12065 0.3048)
			(stroke
				(width 0.1)
				(type default)
			)
			(layer "F.Fab")
		)
		(fp_line
			(start -0.12065 -0.2794)
			(end 0.12065 -0.2794)
			(stroke
				(width 0.1)
				(type default)
			)
			(layer "F.Fab")
		)
		(fp_line
			(start -0.12065 -0.305054)
			(end -0.12065 -0.2794)
			(stroke
				(width 0.1)
				(type default)
			)
			(layer "F.Fab")
		)
		(fp_line
			(start -0.67945 0.3048)
			(end -0.67945 -0.305054)
			(stroke
				(width 0.1)
				(type default)
			)
			(layer "F.Fab")
		)
		(fp_line
			(start -0.67945 -0.305054)
			(end -0.12065 -0.305054)
			(stroke
				(width 0.1)
				(type default)
			)
			(layer "F.Fab")
		)
		(pad "1" smd circle
			(at -0.40005 0 180)
			(size 0 0)
			(layers "F.Cu" "F.Mask" "F.Paste")
			(net "P3V3_OCP_V3_2")
		)
		(pad "2" smd circle
			(at 0.40005 0 180)
			(size 0 0)
			(layers "F.Cu" "F.Mask" "F.Paste")
			(net "IRQ_LVC3_OCP_V3_2_WAKE_N")
		)
	)
)
